(kicad_pcb
	(version 20260206)
	(generator "pcbnew")
	(generator_version "10.0")
	(general
		(thickness 1.6)
		(legacy_teardrops no)
	)
	(paper "A4")
	(title_block
		(title "timecard-production-celestica-r4006 — R4006-B0001-02_R01.brd")
		(comment 1 "Time Appliance Project (Time Card) / footprints 504-510 of 1113")
	)
	(layers
		(0 "F.Cu" signal "TOP")
		(4 "In1.Cu" signal "L02_GND1")
		(6 "In2.Cu" signal "L03_SIG1")
		(8 "In3.Cu" signal "L04_GND2")
		(10 "In4.Cu" signal "L05_VCC1")
		(12 "In5.Cu" signal "L06_VCC2")
		(14 "In6.Cu" signal "L07_GND3")
		(16 "In7.Cu" signal "L08_SIG2")
		(18 "In8.Cu" signal "L09_GND4")
		(2 "B.Cu" signal "BOTTOM")
		(9 "F.Adhes" user "F.Adhesive")
		(11 "B.Adhes" user "B.Adhesive")
		(13 "F.Paste" user "Package Geometry/Pastemask Top")
		(15 "B.Paste" user "Package Geometry/Pastemask Bottom")
		(5 "F.SilkS" user "Ref Des/Silkscreen Top")
		(7 "B.SilkS" user "Ref Des/Silkscreen Bottom")
		(1 "F.Mask" user "Board Geometry/Soldermask Top")
		(3 "B.Mask" user "Board Geometry/Soldermask Bottom")
		(17 "Dwgs.User" user "User.Drawings")
		(19 "Cmts.User" user "User.Comments")
		(21 "Eco1.User" user "User.Eco1")
		(23 "Eco2.User" user "User.Eco2")
		(25 "Edge.Cuts" user "Board Geometry/Outline")
		(27 "Margin" user)
		(31 "F.CrtYd" user "Package Geometry/Place Bound Top")
		(29 "B.CrtYd" user "Package Geometry/Place Bound Bottom")
		(35 "F.Fab" user "Ref Des/Assembly Top")
		(33 "B.Fab" user "Ref Des/Assembly Bottom")
	)
	(footprint ""
		(layer "F.Cu")
		(at 29.337 -94.234 -90)
		(property "Reference" "R128"
			(at -4.953 0.84963 90)
			(unlocked yes)
			(layer "F.SilkS")
			(effects
				(font
					(size 0.7874 0.5842)
					(thickness 0.1524)
				)
			)
		)
		(property "Value" "VAL*"
			(at 0.02032 2.13233 270)
			(unlocked yes)
			(layer "F.Fab")
			(hide yes)
			(effects
				(font
					(size 0.7874 0.5842)
					(thickness 0.1524)
				)
			)
		)
		(property "Tolerance" "TOL*"
			(at 0.044704 3.05435 270)
			(unlocked yes)
			(layer "Cmts.User")
			(hide yes)
			(effects
				(font
					(size 0.7874 0.5842)
					(thickness 0.1524)
				)
			)
		)
		(property "User Part Number" "PARTNUM*"
			(at 0.02032 4.024884 270)
			(unlocked yes)
			(layer "Cmts.User")
			(hide yes)
			(effects
				(font
					(size 0.7874 0.5842)
					(thickness 0.1524)
				)
			)
		)
		(property "Device Type" "RESISTOR-G155-100R0-J0,0OHM,-"
			(at 0.008382 1.210564 270)
			(unlocked yes)
			(layer "F.Fab")
			(hide yes)
			(effects
				(font
					(size 0.7874 0.5842)
					(thickness 0.1524)
				)
			)
		)
		(duplicate_pad_numbers_are_jumpers no)
		(fp_line
			(start -1.143 0.5588)
			(end 1.143 0.5588)
			(stroke
				(width 0.1)
				(type default)
			)
			(layer "F.SilkS")
		)
		(fp_line
			(start 1.143 0.5588)
			(end 1.143 -0.5588)
			(stroke
				(width 0.1)
				(type default)
			)
			(layer "F.SilkS")
		)
		(fp_line
			(start -1.143 -0.5588)
			(end -1.143 0.5588)
			(stroke
				(width 0.1)
				(type default)
			)
			(layer "F.SilkS")
		)
		(fp_line
			(start 1.143 -0.5588)
			(end -1.143 -0.5588)
			(stroke
				(width 0.1)
				(type default)
			)
			(layer "F.SilkS")
		)
		(fp_poly
			(pts
				(xy -1.143 0.5588) (xy 1.143 0.5588) (xy 1.143 -0.5588) (xy -1.143 -0.5588)
			)
			(stroke
				(width 0)
				(type default)
			)
			(fill no)
			(layer "F.CrtYd")
		)
		(fp_line
			(start -0.508 0.3048)
			(end 0.508 0.3048)
			(stroke
				(width 0.1)
				(type default)
			)
			(layer "F.Fab")
		)
		(fp_line
			(start 0.508 0.3048)
			(end 0.508 -0.3048)
			(stroke
				(width 0.1)
				(type default)
			)
			(layer "F.Fab")
		)
		(fp_line
			(start -0.508 -0.3048)
			(end -0.508 0.3048)
			(stroke
				(width 0.1)
				(type default)
			)
			(layer "F.Fab")
		)
		(fp_line
			(start 0.508 -0.3048)
			(end -0.508 -0.3048)
			(stroke
				(width 0.1)
				(type default)
			)
			(layer "F.Fab")
		)
		(pad "1" smd rect
			(at -0.5334 0 270)
			(size 0.7112 0.6096)
			(layers "F.Cu" "F.Mask" "F.Paste")
			(net "FT_USB_DM")
		)
		(pad "2" smd rect
			(at 0.5334 0 270)
			(size 0.7112 0.6096)
			(layers "F.Cu" "F.Mask" "F.Paste")
			(net "R_FT_USB_DM")
		)
		(zone
			(layer "F.Cu")
			(hatch none 0.5)
			(connect_pads
				(clearance 0)
			)
			(min_thickness 0.25)
			(keepout
				(tracks not_allowed)
				(vias allowed)
				(pads allowed)
				(copperpour not_allowed)
				(footprints allowed)
			)
			(placement
				(enabled no)
				(sheetname "")
			)
			(fill
				(thermal_gap 0.5)
				(thermal_bridge_width 0.5)
				(island_removal_mode 0)
			)
			(polygon
				(pts
					(xy 29.0322 -94.3102) (xy 29.0322 -94.1578) (xy 29.6418 -94.1578) (xy 29.6418 -94.3102)
				)
			)
		)
		(zone
			(layer "F.Cu")
			(hatch none 0.5)
			(connect_pads
				(clearance 0)
			)
			(min_thickness 0.25)
			(keepout
				(tracks allowed)
				(vias not_allowed)
				(pads allowed)
				(copperpour not_allowed)
				(footprints allowed)
			)
			(placement
				(enabled no)
				(sheetname "")
			)
			(fill
				(thermal_gap 0.5)
				(thermal_bridge_width 0.5)
				(island_removal_mode 0)
			)
			(polygon
				(pts
					(xy 29.0322 -94.3102) (xy 29.0322 -94.1578) (xy 29.6418 -94.1578) (xy 29.6418 -94.3102)
				)
			)
		)
	)
	(footprint ""
		(layer "F.Cu")
		(at 42.4434 -103.9114)
		(property "Reference" "C33"
			(at 3.9116 -1.59893 0)
			(unlocked yes)
			(layer "F.SilkS")
			(effects
				(font
					(size 0.7874 0.5842)
					(thickness 0.1524)
				)
			)
		)
		(property "Value" "VAL*"
			(at 0.0762 2.067306 0)
			(unlocked yes)
			(layer "F.Fab")
			(hide yes)
			(effects
				(font
					(size 0.7874 0.5842)
					(thickness 0.1524)
				)
			)
		)
		(property "Device Type" "CAPACITOR-G105-0B104-EK,0.1UF,A"
			(at 0.0508 1.127506 0)
			(unlocked yes)
			(layer "F.Fab")
			(hide yes)
			(effects
				(font
					(size 0.7874 0.5842)
					(thickness 0.1524)
				)
			)
		)
		(property "User Part Number" "PARTNUM*"
			(at 0.1016 4.023106 0)
			(unlocked yes)
			(layer "Cmts.User")
			(hide yes)
			(effects
				(font
					(size 0.7874 0.5842)
					(thickness 0.1524)
				)
			)
		)
		(property "Tolerance" "TOL*"
			(at 0.0762 3.032506 0)
			(unlocked yes)
			(layer "Cmts.User")
			(hide yes)
			(effects
				(font
					(size 0.7874 0.5842)
					(thickness 0.1524)
				)
			)
		)
		(duplicate_pad_numbers_are_jumpers no)
		(fp_line
			(start -1.143 -0.5588)
			(end -1.143 0.5588)
			(stroke
				(width 0.1)
				(type default)
			)
			(layer "F.SilkS")
		)
		(fp_line
			(start -1.143 0.5588)
			(end 1.143 0.5588)
			(stroke
				(width 0.1)
				(type default)
			)
			(layer "F.SilkS")
		)
		(fp_line
			(start 1.143 -0.5588)
			(end -1.143 -0.5588)
			(stroke
				(width 0.1)
				(type default)
			)
			(layer "F.SilkS")
		)
		(fp_line
			(start 1.143 0.5588)
			(end 1.143 -0.5588)
			(stroke
				(width 0.1)
				(type default)
			)
			(layer "F.SilkS")
		)
		(fp_rect
			(start 1.143 -0.5588)
			(end -1.143 0.5588)
			(stroke
				(width 0)
				(type default)
			)
			(fill no)
			(layer "F.CrtYd")
		)
		(fp_line
			(start -0.508 -0.3048)
			(end -0.508 0.3048)
			(stroke
				(width 0.1)
				(type default)
			)
			(layer "F.Fab")
		)
		(fp_line
			(start -0.508 0.3048)
			(end 0.508 0.3048)
			(stroke
				(width 0.1)
				(type default)
			)
			(layer "F.Fab")
		)
		(fp_line
			(start 0.508 -0.3048)
			(end -0.508 -0.3048)
			(stroke
				(width 0.1)
				(type default)
			)
			(layer "F.Fab")
		)
		(fp_line
			(start 0.508 0.3048)
			(end 0.508 -0.3048)
			(stroke
				(width 0.1)
				(type default)
			)
			(layer "F.Fab")
		)
		(pad "1" smd rect
			(at -0.5334 0)
			(size 0.7112 0.6096)
			(layers "F.Cu" "F.Mask" "F.Paste")
			(net "VIN_XP5R0V")
		)
		(pad "2" smd rect
			(at 0.5334 0)
			(size 0.7112 0.6096)
			(layers "F.Cu" "F.Mask" "F.Paste")
			(net "SG")
		)
		(zone
			(layer "F.Cu")
			(hatch none 0.5)
			(connect_pads
				(clearance 0)
			)
			(min_thickness 0.25)
			(keepout
				(tracks allowed)
				(vias not_allowed)
				(pads allowed)
				(copperpour not_allowed)
				(footprints allowed)
			)
			(placement
				(enabled no)
				(sheetname "")
			)
			(fill
				(thermal_gap 0.5)
				(thermal_bridge_width 0.5)
				(island_removal_mode 0)
			)
			(polygon
				(pts
					(xy 42.5196 -104.2162) (xy 42.3672 -104.2162) (xy 42.3672 -103.6066) (xy 42.5196 -103.6066)
				)
			)
		)
	)
	(footprint ""
		(layer "F.Cu")
		(at 87.249 -64.3128 90)
		(property "Reference" "C281"
			(at 13.2842 -9.61263 90)
			(unlocked yes)
			(layer "F.SilkS")
			(effects
				(font
					(size 0.7874 0.5842)
					(thickness 0.1524)
				)
			)
		)
		(property "Value" "VAL*"
			(at 0.0762 2.067306 90)
			(unlocked yes)
			(layer "F.Fab")
			(hide yes)
			(effects
				(font
					(size 0.7874 0.5842)
					(thickness 0.1524)
				)
			)
		)
		(property "Device Type" "CAPACITOR-G105-0B104-EK,0.1UF,A"
			(at 0.0508 1.127506 90)
			(unlocked yes)
			(layer "F.Fab")
			(hide yes)
			(effects
				(font
					(size 0.7874 0.5842)
					(thickness 0.1524)
				)
			)
		)
		(property "User Part Number" "PARTNUM*"
			(at 0.1016 4.023106 90)
			(unlocked yes)
			(layer "Cmts.User")
			(hide yes)
			(effects
				(font
					(size 0.7874 0.5842)
					(thickness 0.1524)
				)
			)
		)
		(property "Tolerance" "TOL*"
			(at 0.0762 3.032506 90)
			(unlocked yes)
			(layer "Cmts.User")
			(hide yes)
			(effects
				(font
					(size 0.7874 0.5842)
					(thickness 0.1524)
				)
			)
		)
		(duplicate_pad_numbers_are_jumpers no)
		(fp_line
			(start 1.143 -0.5588)
			(end -1.143 -0.5588)
			(stroke
				(width 0.1)
				(type default)
			)
			(layer "F.SilkS")
		)
		(fp_line
			(start -1.143 -0.5588)
			(end -1.143 0.5588)
			(stroke
				(width 0.1)
				(type default)
			)
			(layer "F.SilkS")
		)
		(fp_line
			(start 1.143 0.5588)
			(end 1.143 -0.5588)
			(stroke
				(width 0.1)
				(type default)
			)
			(layer "F.SilkS")
		)
		(fp_line
			(start -1.143 0.5588)
			(end 1.143 0.5588)
			(stroke
				(width 0.1)
				(type default)
			)
			(layer "F.SilkS")
		)
		(fp_rect
			(start -1.143 -0.5588)
			(end 1.143 0.5588)
			(stroke
				(width 0)
				(type default)
			)
			(fill no)
			(layer "F.CrtYd")
		)
		(fp_line
			(start 0.508 -0.3048)
			(end -0.508 -0.3048)
			(stroke
				(width 0.1)
				(type default)
			)
			(layer "F.Fab")
		)
		(fp_line
			(start -0.508 -0.3048)
			(end -0.508 0.3048)
			(stroke
				(width 0.1)
				(type default)
			)
			(layer "F.Fab")
		)
		(fp_line
			(start 0.508 0.3048)
			(end 0.508 -0.3048)
			(stroke
				(width 0.1)
				(type default)
			)
			(layer "F.Fab")
		)
		(fp_line
			(start -0.508 0.3048)
			(end 0.508 0.3048)
			(stroke
				(width 0.1)
				(type default)
			)
			(layer "F.Fab")
		)
		(pad "1" smd rect
			(at -0.5334 0 90)
			(size 0.7112 0.6096)
			(layers "F.Cu" "F.Mask" "F.Paste")
			(net "VDD_BNO085")
		)
		(pad "2" smd rect
			(at 0.5334 0 90)
			(size 0.7112 0.6096)
			(layers "F.Cu" "F.Mask" "F.Paste")
			(net "SG")
		)
		(zone
			(layer "F.Cu")
			(hatch none 0.5)
			(connect_pads
				(clearance 0)
			)
			(min_thickness 0.25)
			(keepout
				(tracks allowed)
				(vias not_allowed)
				(pads allowed)
				(copperpour not_allowed)
				(footprints allowed)
			)
			(placement
				(enabled no)
				(sheetname "")
			)
			(fill
				(thermal_gap 0.5)
				(thermal_bridge_width 0.5)
				(island_removal_mode 0)
			)
			(polygon
				(pts
					(xy 86.9442 -64.2366) (xy 87.5538 -64.2366) (xy 87.5538 -64.389) (xy 86.9442 -64.389)
				)
			)
		)
	)
	(footprint ""
		(layer "F.Cu")
		(at 49.784 -131.572)
		(property "Reference" "SP52"
			(at 0 0 0)
			(layer "F.SilkS")
			(hide yes)
			(effects
				(font
					(size 1.27 1.27)
				)
			)
		)
		(property "Value" ""
			(at 0 0 0)
			(layer "F.Fab")
			(effects
				(font
					(size 1.27 1.27)
				)
			)
		)
		(duplicate_pad_numbers_are_jumpers no)
	)
	(footprint ""
		(layer "F.Cu")
		(at 41.656 -80.518 180)
		(property "Reference" "CR2"
			(at 0.635 4.40563 0)
			(unlocked yes)
			(layer "F.SilkS")
			(effects
				(font
					(size 0.7874 0.5842)
					(thickness 0.1524)
				)
			)
		)
		(property "Value" ""
			(at 0 0 180)
			(layer "F.Fab")
			(effects
				(font
					(size 1.27 1.27)
				)
			)
		)
		(property "Device Type" "DIODE_2F-G122-10186-01"
			(at 0 2.037842 180)
			(unlocked yes)
			(layer "F.Fab")
			(hide yes)
			(effects
				(font
					(size 0.7874 0.5842)
					(thickness 0.000001)
				)
			)
		)
		(property "User Part Number" "PARTNUM*"
			(at 0 3.231642 180)
			(unlocked yes)
			(layer "Cmts.User")
			(hide yes)
			(effects
				(font
					(size 0.7874 0.5842)
					(thickness 0.000001)
				)
			)
		)
		(duplicate_pad_numbers_are_jumpers no)
		(fp_line
			(start 1.608074 0.928878)
			(end -1.608074 0.928878)
			(stroke
				(width 0.1)
				(type default)
			)
			(layer "F.SilkS")
		)
		(fp_line
			(start 1.608074 -0.928878)
			(end 1.608074 0.928878)
			(stroke
				(width 0.1)
				(type default)
			)
			(layer "F.SilkS")
		)
		(fp_line
			(start -1.608074 0.928878)
			(end -1.608074 -0.928878)
			(stroke
				(width 0.1)
				(type default)
			)
			(layer "F.SilkS")
		)
		(fp_line
			(start -1.608074 -0.928878)
			(end 1.608074 -0.928878)
			(stroke
				(width 0.1)
				(type default)
			)
			(layer "F.SilkS")
		)
		(fp_poly
			(pts
				(xy -2.116074 -0.928878) (xy -2.116074 0.928878) (xy -1.608074 0.928878) (xy -1.608074 -0.928878)
			)
			(stroke
				(width 0)
				(type default)
			)
			(fill yes)
			(layer "F.SilkS")
		)
		(fp_poly
			(pts
				(xy -2.116074 1.182878) (xy 1.862074 1.182878) (xy 1.862074 -1.182878) (xy -2.116074 -1.182878)
			)
			(stroke
				(width 0)
				(type default)
			)
			(fill no)
			(layer "F.CrtYd")
		)
		(fp_line
			(start 0.899922 0.674878)
			(end -0.899922 0.674878)
			(stroke
				(width 0.1)
				(type default)
			)
			(layer "F.Fab")
		)
		(fp_line
			(start 0.899922 -0.674878)
			(end 0.899922 0.674878)
			(stroke
				(width 0.1)
				(type default)
			)
			(layer "F.Fab")
		)
		(fp_line
			(start -0.899922 0.674878)
			(end -0.899922 -0.674878)
			(stroke
				(width 0.1)
				(type default)
			)
			(layer "F.Fab")
		)
		(fp_line
			(start -0.899922 -0.674878)
			(end 0.899922 -0.674878)
			(stroke
				(width 0.1)
				(type default)
			)
			(layer "F.Fab")
		)
		(fp_poly
			(pts
				(xy -0.899922 -0.674878) (xy -0.899922 0.674878) (xy -0.391922 0.674878) (xy -0.391922 -0.674878)
			)
			(stroke
				(width 0)
				(type default)
			)
			(fill yes)
			(layer "F.Fab")
		)
		(fp_text user "A"
			(at 2.413 0.59563 0)
			(unlocked yes)
			(layer "F.SilkS")
			(effects
				(font
					(size 0.7874 0.5842)
					(thickness 0.1524)
				)
			)
		)
		(fp_text user "C"
			(at -2.032 -1.68275 0)
			(unlocked yes)
			(layer "F.SilkS")
			(effects
				(font
					(size 0.635 0.4064)
					(thickness 0.1524)
				)
			)
		)
		(fp_text user "A"
			(at 2.262124 0.156718 0)
			(unlocked yes)
			(layer "F.Fab")
			(effects
				(font
					(size 0.7874 0.5842)
					(thickness 0.1524)
				)
			)
		)
		(fp_text user "C"
			(at -1.778 0.97663 0)
			(unlocked yes)
			(layer "F.Fab")
			(effects
				(font
					(size 0.7874 0.5842)
					(thickness 0.1524)
				)
			)
		)
		(pad "A" smd rect
			(at 1.100074 0 180)
			(size 0.508 0.508)
			(layers "F.Cu" "F.Mask" "F.Paste")
			(net "XP5R0V_FT4232")
		)
		(pad "C" smd rect
			(at -1.100074 0 180)
			(size 0.508 0.508)
			(layers "F.Cu" "F.Mask" "F.Paste")
			(net "UNNAMED_525_CAPACITOR_I7_1")
		)
	)
	(footprint ""
		(layer "F.Cu")
		(at 57.531 -129.54)
		(property "Reference" "SP58"
			(at 0 0 0)
			(layer "F.SilkS")
			(hide yes)
			(effects
				(font
					(size 1.27 1.27)
				)
			)
		)
		(property "Value" ""
			(at 0 0 0)
			(layer "F.Fab")
			(effects
				(font
					(size 1.27 1.27)
				)
			)
		)
		(duplicate_pad_numbers_are_jumpers no)
	)
	(footprint ""
		(layer "F.Cu")
		(at 19.468338 -49.022 180)
		(property "Reference" "R395"
			(at -3.518662 0.21463 0)
			(unlocked yes)
			(layer "F.SilkS")
			(effects
				(font
					(size 0.7874 0.5842)
					(thickness 0.1524)
				)
			)
		)
		(property "Value" "VAL*"
			(at 0.02032 2.13233 180)
			(unlocked yes)
			(layer "F.Fab")
			(hide yes)
			(effects
				(font
					(size 0.7874 0.5842)
					(thickness 0.1524)
				)
			)
		)
		(property "Tolerance" "TOL*"
			(at 0.044704 3.05435 180)
			(unlocked yes)
			(layer "Cmts.User")
			(hide yes)
			(effects
				(font
					(size 0.7874 0.5842)
					(thickness 0.1524)
				)
			)
		)
		(property "User Part Number" "PARTNUM*"
			(at 0.02032 4.024884 180)
			(unlocked yes)
			(layer "Cmts.User")
			(hide yes)
			(effects
				(font
					(size 0.7874 0.5842)
					(thickness 0.1524)
				)
			)
		)
		(property "Device Type" "RESISTOR-G155-133R0-01,33OHM,1%"
			(at 0.008382 1.210564 180)
			(unlocked yes)
			(layer "F.Fab")
			(hide yes)
			(effects
				(font
					(size 0.7874 0.5842)
					(thickness 0.1524)
				)
			)
		)
		(duplicate_pad_numbers_are_jumpers no)
		(fp_line
			(start 1.143 0.5588)
			(end 1.143 -0.5588)
			(stroke
				(width 0.1)
				(type default)
			)
			(layer "F.SilkS")
		)
		(fp_line
			(start 1.143 -0.5588)
			(end -1.143 -0.5588)
			(stroke
				(width 0.1)
				(type default)
			)
			(layer "F.SilkS")
		)
		(fp_line
			(start -1.143 0.5588)
			(end 1.143 0.5588)
			(stroke
				(width 0.1)
				(type default)
			)
			(layer "F.SilkS")
		)
		(fp_line
			(start -1.143 -0.5588)
			(end -1.143 0.5588)
			(stroke
				(width 0.1)
				(type default)
			)
			(layer "F.SilkS")
		)
		(fp_rect
			(start -1.143 -0.5588)
			(end 1.143 0.5588)
			(stroke
				(width 0)
				(type default)
			)
			(fill no)
			(layer "F.CrtYd")
		)
		(fp_line
			(start 0.508 0.3048)
			(end 0.508 -0.3048)
			(stroke
				(width 0.1)
				(type default)
			)
			(layer "F.Fab")
		)
		(fp_line
			(start 0.508 -0.3048)
			(end -0.508 -0.3048)
			(stroke
				(width 0.1)
				(type default)
			)
			(layer "F.Fab")
		)
		(fp_line
			(start -0.508 0.3048)
			(end 0.508 0.3048)
			(stroke
				(width 0.1)
				(type default)
			)
			(layer "F.Fab")
		)
		(fp_line
			(start -0.508 -0.3048)
			(end -0.508 0.3048)
			(stroke
				(width 0.1)
				(type default)
			)
			(layer "F.Fab")
		)
		(pad "1" smd rect
			(at -0.5334 0 180)
			(size 0.7112 0.6096)
			(layers "F.Cu" "F.Mask" "F.Paste")
			(net "SMA4_LED_GREEN_N")
		)
		(pad "2" smd rect
			(at 0.5334 0 180)
			(size 0.7112 0.6096)
			(layers "F.Cu" "F.Mask" "F.Paste")
			(net "UNNAMED_14_LED4PV14_I268_4")
		)
		(zone
			(layer "F.Cu")
			(hatch none 0.5)
			(connect_pads
				(clearance 0)
			)
			(min_thickness 0.25)
			(keepout
				(tracks not_allowed)
				(vias allowed)
				(pads allowed)
				(copperpour not_allowed)
				(footprints allowed)
			)
			(placement
				(enabled no)
				(sheetname "")
			)
			(fill
				(thermal_gap 0.5)
				(thermal_bridge_width 0.5)
				(island_removal_mode 0)
			)
			(polygon
				(pts
					(xy 19.544538 -48.7172) (xy 19.544538 -49.3268) (xy 19.392138 -49.3268) (xy 19.392138 -48.7172)
				)
			)
		)
		(zone
			(layer "F.Cu")
			(hatch none 0.5)
			(connect_pads
				(clearance 0)
			)
			(min_thickness 0.25)
			(keepout
				(tracks allowed)
				(vias not_allowed)
				(pads allowed)
				(copperpour not_allowed)
				(footprints allowed)
			)
			(placement
				(enabled no)
				(sheetname "")
			)
			(fill
				(thermal_gap 0.5)
				(thermal_bridge_width 0.5)
				(island_removal_mode 0)
			)
			(polygon
				(pts
					(xy 19.544538 -48.7172) (xy 19.544538 -49.3268) (xy 19.392138 -49.3268) (xy 19.392138 -48.7172)
				)
			)
		)
	)
)
